(kicad_pcb
	(version 20260206)
	(generator "pcbnew")
	(generator_version "10.0")
	(general
		(thickness 1.6)
		(legacy_teardrops no)
	)
	(paper "A4")
	(title_block
		(title "01162023_DA0F0TEBIF0_F0T_Expander_BD_F_brd_V02_OCP.brd")
		(comment 1 "Grand Teton / footprints 6734-6740 of 9728")
	)
	(layers
		(0 "F.Cu" signal "TOP")
		(4 "In1.Cu" signal "GND")
		(6 "In2.Cu" signal "VCC")
		(8 "In3.Cu" signal "VCC1")
		(10 "In4.Cu" signal "GND1")
		(12 "In5.Cu" signal "IN1")
		(14 "In6.Cu" signal "GND2")
		(16 "In7.Cu" signal "IN2")
		(18 "In8.Cu" signal "GND3")
		(20 "In9.Cu" signal "IN3")
		(22 "In10.Cu" signal "GND4")
		(24 "In11.Cu" signal "IN4")
		(26 "In12.Cu" signal "GND5")
		(28 "In13.Cu" signal "IN5")
		(30 "In14.Cu" signal "GND6")
		(32 "In15.Cu" signal "IN6")
		(34 "In16.Cu" signal "GND7")
		(2 "B.Cu" signal "BOTTOM")
		(9 "F.Adhes" user "F.Adhesive")
		(11 "B.Adhes" user "B.Adhesive")
		(13 "F.Paste" user "Package Geometry/Pastemask Top")
		(15 "B.Paste" user "Package Geometry/Pastemask Bottom")
		(5 "F.SilkS" user "Ref Des/Silkscreen Top")
		(7 "B.SilkS" user "Ref Des/Silkscreen Bottom")
		(1 "F.Mask" user "Board Geometry/Soldermask Top")
		(3 "B.Mask" user "Board Geometry/Soldermask Bottom")
		(17 "Dwgs.User" user "User.Drawings")
		(19 "Cmts.User" user "User.Comments")
		(21 "Eco1.User" user "User.Eco1")
		(23 "Eco2.User" user "User.Eco2")
		(25 "Edge.Cuts" user "Board Geometry/Outline")
		(27 "Margin" user)
		(31 "F.CrtYd" user "Package Geometry/Place Bound Top")
		(29 "B.CrtYd" user "Package Geometry/Place Bound Bottom")
		(35 "F.Fab" user "Ref Des/Assembly Top")
		(33 "B.Fab" user "Ref Des/Assembly Bottom")
	)
	(footprint ""
		(layer "F.Cu")
		(at 8.120634 -26.666444 -90)
		(property "Reference" "R4051"
			(at 0 0 270)
			(layer "F.SilkS")
			(hide yes)
			(effects
				(font
					(size 1.27 1.27)
				)
			)
		)
		(property "Value" ""
			(at 0 0 270)
			(layer "F.Fab")
			(effects
				(font
					(size 1.27 1.27)
				)
			)
		)
		(duplicate_pad_numbers_are_jumpers no)
		(fp_line
			(start -0.7874 0.4064)
			(end -0.7874 -0.4064)
			(stroke
				(width 0.1524)
				(type default)
			)
			(layer "F.SilkS")
		)
		(fp_line
			(start 0.7874 0.4064)
			(end -0.7874 0.4064)
			(stroke
				(width 0.1524)
				(type default)
			)
			(layer "F.SilkS")
		)
		(fp_line
			(start -0.7874 -0.4064)
			(end 0.7874 -0.4064)
			(stroke
				(width 0.1524)
				(type default)
			)
			(layer "F.SilkS")
		)
		(fp_line
			(start 0.7874 -0.4064)
			(end 0.7874 0.4064)
			(stroke
				(width 0.1524)
				(type default)
			)
			(layer "F.SilkS")
		)
		(fp_line
			(start -0.67945 0.3048)
			(end -0.67945 -0.305054)
			(stroke
				(width 0.1)
				(type default)
			)
			(layer "F.Fab")
		)
		(fp_line
			(start -0.12065 0.3048)
			(end -0.67945 0.3048)
			(stroke
				(width 0.1)
				(type default)
			)
			(layer "F.Fab")
		)
		(fp_line
			(start 0.120396 0.3048)
			(end 0.120396 0.2794)
			(stroke
				(width 0.1)
				(type default)
			)
			(layer "F.Fab")
		)
		(fp_line
			(start 0.67945 0.3048)
			(end 0.120396 0.3048)
			(stroke
				(width 0.1)
				(type default)
			)
			(layer "F.Fab")
		)
		(fp_line
			(start -0.12065 0.2794)
			(end -0.12065 0.3048)
			(stroke
				(width 0.1)
				(type default)
			)
			(layer "F.Fab")
		)
		(fp_line
			(start 0.120396 0.2794)
			(end -0.12065 0.2794)
			(stroke
				(width 0.1)
				(type default)
			)
			(layer "F.Fab")
		)
		(fp_line
			(start -0.12065 -0.2794)
			(end 0.12065 -0.2794)
			(stroke
				(width 0.1)
				(type default)
			)
			(layer "F.Fab")
		)
		(fp_line
			(start 0.12065 -0.2794)
			(end 0.12065 -0.3048)
			(stroke
				(width 0.1)
				(type default)
			)
			(layer "F.Fab")
		)
		(fp_line
			(start 0.12065 -0.3048)
			(end 0.67945 -0.3048)
			(stroke
				(width 0.1)
				(type default)
			)
			(layer "F.Fab")
		)
		(fp_line
			(start 0.67945 -0.3048)
			(end 0.67945 0.3048)
			(stroke
				(width 0.1)
				(type default)
			)
			(layer "F.Fab")
		)
		(fp_line
			(start -0.67945 -0.305054)
			(end -0.12065 -0.305054)
			(stroke
				(width 0.1)
				(type default)
			)
			(layer "F.Fab")
		)
		(fp_line
			(start -0.12065 -0.305054)
			(end -0.12065 -0.2794)
			(stroke
				(width 0.1)
				(type default)
			)
			(layer "F.Fab")
		)
		(pad "1" smd circle
			(at -0.40005 0 270)
			(size 0 0)
			(layers "F.Cu" "F.Mask" "F.Paste")
			(net "PRSNT_SSD0_R_N")
		)
		(pad "2" smd circle
			(at 0.40005 0 270)
			(size 0 0)
			(layers "F.Cu" "F.Mask" "F.Paste")
			(net "PRSNT_SSD0_N")
		)
	)
	(footprint ""
		(layer "F.Cu")
		(at 121.494296 -29.507688 -90)
		(property "Reference" "PC921"
			(at 0 0 270)
			(layer "F.SilkS")
			(hide yes)
			(effects
				(font
					(size 1.27 1.27)
				)
			)
		)
		(property "Value" ""
			(at 0 0 270)
			(layer "F.Fab")
			(effects
				(font
					(size 1.27 1.27)
				)
			)
		)
		(duplicate_pad_numbers_are_jumpers no)
		(fp_line
			(start -1.524 0.762)
			(end -1.524 -0.762)
			(stroke
				(width 0.1524)
				(type default)
			)
			(layer "F.SilkS")
		)
		(fp_line
			(start 1.524 0.762)
			(end -1.524 0.762)
			(stroke
				(width 0.1524)
				(type default)
			)
			(layer "F.SilkS")
		)
		(fp_line
			(start -1.524 -0.762)
			(end 1.524 -0.762)
			(stroke
				(width 0.1524)
				(type default)
			)
			(layer "F.SilkS")
		)
		(fp_line
			(start 1.524 -0.762)
			(end 1.524 0.762)
			(stroke
				(width 0.1524)
				(type default)
			)
			(layer "F.SilkS")
		)
		(fp_line
			(start -1.1049 0.724916)
			(end 1.1049 0.724916)
			(stroke
				(width 0.1)
				(type default)
			)
			(layer "F.Fab")
		)
		(fp_line
			(start 1.1049 0.724916)
			(end 1.1049 -0.724916)
			(stroke
				(width 0.1)
				(type default)
			)
			(layer "F.Fab")
		)
		(fp_line
			(start -1.1049 -0.724916)
			(end -1.1049 0.724916)
			(stroke
				(width 0.1)
				(type default)
			)
			(layer "F.Fab")
		)
		(fp_line
			(start 1.1049 -0.724916)
			(end -1.1049 -0.724916)
			(stroke
				(width 0.1)
				(type default)
			)
			(layer "F.Fab")
		)
		(pad "1" smd rect
			(at -0.889 0 90)
			(size 1.016 1.27)
			(layers "F.Cu" "F.Mask" "F.Paste")
			(net "P3V3_SSD4")
		)
		(pad "2" smd rect
			(at 0.889 0 90)
			(size 1.016 1.27)
			(layers "F.Cu" "F.Mask" "F.Paste")
			(net "GND")
		)
	)
	(footprint ""
		(layer "F.Cu")
		(at 135.346948 -38.49116 180)
		(property "Reference" "R6065"
			(at 0 0 180)
			(layer "F.SilkS")
			(hide yes)
			(effects
				(font
					(size 1.27 1.27)
				)
			)
		)
		(property "Value" ""
			(at 0 0 180)
			(layer "F.Fab")
			(effects
				(font
					(size 1.27 1.27)
				)
			)
		)
		(duplicate_pad_numbers_are_jumpers no)
		(fp_line
			(start 0.7874 0.4064)
			(end -0.7874 0.4064)
			(stroke
				(width 0.1524)
				(type default)
			)
			(layer "F.SilkS")
		)
		(fp_line
			(start 0.7874 -0.4064)
			(end 0.7874 0.4064)
			(stroke
				(width 0.1524)
				(type default)
			)
			(layer "F.SilkS")
		)
		(fp_line
			(start -0.7874 0.4064)
			(end -0.7874 -0.4064)
			(stroke
				(width 0.1524)
				(type default)
			)
			(layer "F.SilkS")
		)
		(fp_line
			(start -0.7874 -0.4064)
			(end 0.7874 -0.4064)
			(stroke
				(width 0.1524)
				(type default)
			)
			(layer "F.SilkS")
		)
		(fp_line
			(start 0.67945 0.3048)
			(end 0.120396 0.3048)
			(stroke
				(width 0.1)
				(type default)
			)
			(layer "F.Fab")
		)
		(fp_line
			(start 0.67945 -0.3048)
			(end 0.67945 0.3048)
			(stroke
				(width 0.1)
				(type default)
			)
			(layer "F.Fab")
		)
		(fp_line
			(start 0.12065 -0.2794)
			(end 0.12065 -0.3048)
			(stroke
				(width 0.1)
				(type default)
			)
			(layer "F.Fab")
		)
		(fp_line
			(start 0.12065 -0.3048)
			(end 0.67945 -0.3048)
			(stroke
				(width 0.1)
				(type default)
			)
			(layer "F.Fab")
		)
		(fp_line
			(start 0.120396 0.3048)
			(end 0.120396 0.2794)
			(stroke
				(width 0.1)
				(type default)
			)
			(layer "F.Fab")
		)
		(fp_line
			(start 0.120396 0.2794)
			(end -0.12065 0.2794)
			(stroke
				(width 0.1)
				(type default)
			)
			(layer "F.Fab")
		)
		(fp_line
			(start -0.12065 0.3048)
			(end -0.67945 0.3048)
			(stroke
				(width 0.1)
				(type default)
			)
			(layer "F.Fab")
		)
		(fp_line
			(start -0.12065 0.2794)
			(end -0.12065 0.3048)
			(stroke
				(width 0.1)
				(type default)
			)
			(layer "F.Fab")
		)
		(fp_line
			(start -0.12065 -0.2794)
			(end 0.12065 -0.2794)
			(stroke
				(width 0.1)
				(type default)
			)
			(layer "F.Fab")
		)
		(fp_line
			(start -0.12065 -0.305054)
			(end -0.12065 -0.2794)
			(stroke
				(width 0.1)
				(type default)
			)
			(layer "F.Fab")
		)
		(fp_line
			(start -0.67945 0.3048)
			(end -0.67945 -0.305054)
			(stroke
				(width 0.1)
				(type default)
			)
			(layer "F.Fab")
		)
		(fp_line
			(start -0.67945 -0.305054)
			(end -0.12065 -0.305054)
			(stroke
				(width 0.1)
				(type default)
			)
			(layer "F.Fab")
		)
		(pad "1" smd circle
			(at -0.40005 0 180)
			(size 0 0)
			(layers "F.Cu" "F.Mask" "F.Paste")
			(net "P3V3_SSD5_PG_G1")
		)
		(pad "2" smd circle
			(at 0.40005 0 180)
			(size 0 0)
			(layers "F.Cu" "F.Mask" "F.Paste")
			(net "GND")
		)
	)
	(footprint ""
		(layer "F.Cu")
		(at 165.75659 -20.467574 180)
		(property "Reference" "R1664"
			(at 0 0 180)
			(layer "F.SilkS")
			(hide yes)
			(effects
				(font
					(size 1.27 1.27)
				)
			)
		)
		(property "Value" ""
			(at 0 0 180)
			(layer "F.Fab")
			(effects
				(font
					(size 1.27 1.27)
				)
			)
		)
		(duplicate_pad_numbers_are_jumpers no)
		(fp_line
			(start 0.7874 0.4064)
			(end -0.7874 0.4064)
			(stroke
				(width 0.1524)
				(type default)
			)
			(layer "F.SilkS")
		)
		(fp_line
			(start 0.7874 -0.4064)
			(end 0.7874 0.4064)
			(stroke
				(width 0.1524)
				(type default)
			)
			(layer "F.SilkS")
		)
		(fp_line
			(start -0.7874 0.4064)
			(end -0.7874 -0.4064)
			(stroke
				(width 0.1524)
				(type default)
			)
			(layer "F.SilkS")
		)
		(fp_line
			(start -0.7874 -0.4064)
			(end 0.7874 -0.4064)
			(stroke
				(width 0.1524)
				(type default)
			)
			(layer "F.SilkS")
		)
		(fp_line
			(start 0.67945 0.3048)
			(end 0.120396 0.3048)
			(stroke
				(width 0.1)
				(type default)
			)
			(layer "F.Fab")
		)
		(fp_line
			(start 0.67945 -0.3048)
			(end 0.67945 0.3048)
			(stroke
				(width 0.1)
				(type default)
			)
			(layer "F.Fab")
		)
		(fp_line
			(start 0.12065 -0.2794)
			(end 0.12065 -0.3048)
			(stroke
				(width 0.1)
				(type default)
			)
			(layer "F.Fab")
		)
		(fp_line
			(start 0.12065 -0.3048)
			(end 0.67945 -0.3048)
			(stroke
				(width 0.1)
				(type default)
			)
			(layer "F.Fab")
		)
		(fp_line
			(start 0.120396 0.3048)
			(end 0.120396 0.2794)
			(stroke
				(width 0.1)
				(type default)
			)
			(layer "F.Fab")
		)
		(fp_line
			(start 0.120396 0.2794)
			(end -0.12065 0.2794)
			(stroke
				(width 0.1)
				(type default)
			)
			(layer "F.Fab")
		)
		(fp_line
			(start -0.12065 0.3048)
			(end -0.67945 0.3048)
			(stroke
				(width 0.1)
				(type default)
			)
			(layer "F.Fab")
		)
		(fp_line
			(start -0.12065 0.2794)
			(end -0.12065 0.3048)
			(stroke
				(width 0.1)
				(type default)
			)
			(layer "F.Fab")
		)
		(fp_line
			(start -0.12065 -0.2794)
			(end 0.12065 -0.2794)
			(stroke
				(width 0.1)
				(type default)
			)
			(layer "F.Fab")
		)
		(fp_line
			(start -0.12065 -0.305054)
			(end -0.12065 -0.2794)
			(stroke
				(width 0.1)
				(type default)
			)
			(layer "F.Fab")
		)
		(fp_line
			(start -0.67945 0.3048)
			(end -0.67945 -0.305054)
			(stroke
				(width 0.1)
				(type default)
			)
			(layer "F.Fab")
		)
		(fp_line
			(start -0.67945 -0.305054)
			(end -0.12065 -0.305054)
			(stroke
				(width 0.1)
				(type default)
			)
			(layer "F.Fab")
		)
		(pad "1" smd circle
			(at -0.40005 0 180)
			(size 0 0)
			(layers "F.Cu" "F.Mask" "F.Paste")
			(net "P3V3_SSD5")
		)
		(pad "2" smd circle
			(at 0.40005 0 180)
			(size 0 0)
			(layers "F.Cu" "F.Mask" "F.Paste")
			(net "SMB_ISO_SSD5_SDA")
		)
	)
	(footprint ""
		(layer "F.Cu")
		(at 452.567802 -52.035456 180)
		(property "Reference" "R877"
			(at 0 0 180)
			(layer "F.SilkS")
			(hide yes)
			(effects
				(font
					(size 1.27 1.27)
				)
			)
		)
		(property "Value" ""
			(at 0 0 180)
			(layer "F.Fab")
			(effects
				(font
					(size 1.27 1.27)
				)
			)
		)
		(duplicate_pad_numbers_are_jumpers no)
		(fp_line
			(start 0.7874 0.4064)
			(end -0.7874 0.4064)
			(stroke
				(width 0.1524)
				(type default)
			)
			(layer "F.SilkS")
		)
		(fp_line
			(start 0.7874 -0.4064)
			(end 0.7874 0.4064)
			(stroke
				(width 0.1524)
				(type default)
			)
			(layer "F.SilkS")
		)
		(fp_line
			(start -0.7874 0.4064)
			(end -0.7874 -0.4064)
			(stroke
				(width 0.1524)
				(type default)
			)
			(layer "F.SilkS")
		)
		(fp_line
			(start -0.7874 -0.4064)
			(end 0.7874 -0.4064)
			(stroke
				(width 0.1524)
				(type default)
			)
			(layer "F.SilkS")
		)
		(fp_line
			(start 0.67945 0.3048)
			(end 0.120396 0.3048)
			(stroke
				(width 0.1)
				(type default)
			)
			(layer "F.Fab")
		)
		(fp_line
			(start 0.67945 -0.3048)
			(end 0.67945 0.3048)
			(stroke
				(width 0.1)
				(type default)
			)
			(layer "F.Fab")
		)
		(fp_line
			(start 0.12065 -0.2794)
			(end 0.12065 -0.3048)
			(stroke
				(width 0.1)
				(type default)
			)
			(layer "F.Fab")
		)
		(fp_line
			(start 0.12065 -0.3048)
			(end 0.67945 -0.3048)
			(stroke
				(width 0.1)
				(type default)
			)
			(layer "F.Fab")
		)
		(fp_line
			(start 0.120396 0.3048)
			(end 0.120396 0.2794)
			(stroke
				(width 0.1)
				(type default)
			)
			(layer "F.Fab")
		)
		(fp_line
			(start 0.120396 0.2794)
			(end -0.12065 0.2794)
			(stroke
				(width 0.1)
				(type default)
			)
			(layer "F.Fab")
		)
		(fp_line
			(start -0.12065 0.3048)
			(end -0.67945 0.3048)
			(stroke
				(width 0.1)
				(type default)
			)
			(layer "F.Fab")
		)
		(fp_line
			(start -0.12065 0.2794)
			(end -0.12065 0.3048)
			(stroke
				(width 0.1)
				(type default)
			)
			(layer "F.Fab")
		)
		(fp_line
			(start -0.12065 -0.2794)
			(end 0.12065 -0.2794)
			(stroke
				(width 0.1)
				(type default)
			)
			(layer "F.Fab")
		)
		(fp_line
			(start -0.12065 -0.305054)
			(end -0.12065 -0.2794)
			(stroke
				(width 0.1)
				(type default)
			)
			(layer "F.Fab")
		)
		(fp_line
			(start -0.67945 0.3048)
			(end -0.67945 -0.305054)
			(stroke
				(width 0.1)
				(type default)
			)
			(layer "F.Fab")
		)
		(fp_line
			(start -0.67945 -0.305054)
			(end -0.12065 -0.305054)
			(stroke
				(width 0.1)
				(type default)
			)
			(layer "F.Fab")
		)
		(pad "1" smd circle
			(at -0.40005 0 180)
			(size 0 0)
			(layers "F.Cu" "F.Mask" "F.Paste")
			(net "P3V3_AUX")
		)
		(pad "2" smd circle
			(at 0.40005 0 180)
			(size 0 0)
			(layers "F.Cu" "F.Mask" "F.Paste")
			(net "PWRGD_P12V_SSD15")
		)
	)
	(footprint ""
		(layer "F.Cu")
		(at 304.687478 -25.342342 -90)
		(property "Reference" "R440"
			(at 0 0 270)
			(layer "F.SilkS")
			(hide yes)
			(effects
				(font
					(size 1.27 1.27)
				)
			)
		)
		(property "Value" ""
			(at 0 0 270)
			(layer "F.Fab")
			(effects
				(font
					(size 1.27 1.27)
				)
			)
		)
		(duplicate_pad_numbers_are_jumpers no)
		(fp_line
			(start -0.7874 0.4064)
			(end -0.7874 -0.4064)
			(stroke
				(width 0.1524)
				(type default)
			)
			(layer "F.SilkS")
		)
		(fp_line
			(start 0.7874 0.4064)
			(end -0.7874 0.4064)
			(stroke
				(width 0.1524)
				(type default)
			)
			(layer "F.SilkS")
		)
		(fp_line
			(start -0.7874 -0.4064)
			(end 0.7874 -0.4064)
			(stroke
				(width 0.1524)
				(type default)
			)
			(layer "F.SilkS")
		)
		(fp_line
			(start 0.7874 -0.4064)
			(end 0.7874 0.4064)
			(stroke
				(width 0.1524)
				(type default)
			)
			(layer "F.SilkS")
		)
		(fp_line
			(start -0.67945 0.3048)
			(end -0.67945 -0.305054)
			(stroke
				(width 0.1)
				(type default)
			)
			(layer "F.Fab")
		)
		(fp_line
			(start -0.12065 0.3048)
			(end -0.67945 0.3048)
			(stroke
				(width 0.1)
				(type default)
			)
			(layer "F.Fab")
		)
		(fp_line
			(start 0.120396 0.3048)
			(end 0.120396 0.2794)
			(stroke
				(width 0.1)
				(type default)
			)
			(layer "F.Fab")
		)
		(fp_line
			(start 0.67945 0.3048)
			(end 0.120396 0.3048)
			(stroke
				(width 0.1)
				(type default)
			)
			(layer "F.Fab")
		)
		(fp_line
			(start -0.12065 0.2794)
			(end -0.12065 0.3048)
			(stroke
				(width 0.1)
				(type default)
			)
			(layer "F.Fab")
		)
		(fp_line
			(start 0.120396 0.2794)
			(end -0.12065 0.2794)
			(stroke
				(width 0.1)
				(type default)
			)
			(layer "F.Fab")
		)
		(fp_line
			(start -0.12065 -0.2794)
			(end 0.12065 -0.2794)
			(stroke
				(width 0.1)
				(type default)
			)
			(layer "F.Fab")
		)
		(fp_line
			(start 0.12065 -0.2794)
			(end 0.12065 -0.3048)
			(stroke
				(width 0.1)
				(type default)
			)
			(layer "F.Fab")
		)
		(fp_line
			(start 0.12065 -0.3048)
			(end 0.67945 -0.3048)
			(stroke
				(width 0.1)
				(type default)
			)
			(layer "F.Fab")
		)
		(fp_line
			(start 0.67945 -0.3048)
			(end 0.67945 0.3048)
			(stroke
				(width 0.1)
				(type default)
			)
			(layer "F.Fab")
		)
		(fp_line
			(start -0.67945 -0.305054)
			(end -0.12065 -0.305054)
			(stroke
				(width 0.1)
				(type default)
			)
			(layer "F.Fab")
		)
		(fp_line
			(start -0.12065 -0.305054)
			(end -0.12065 -0.2794)
			(stroke
				(width 0.1)
				(type default)
			)
			(layer "F.Fab")
		)
		(pad "1" smd circle
			(at -0.40005 0 270)
			(size 0 0)
			(layers "F.Cu" "F.Mask" "F.Paste")
			(net "GND")
		)
		(pad "2" smd circle
			(at 0.40005 0 270)
			(size 0 0)
			(layers "F.Cu" "F.Mask" "F.Paste")
			(net "DUALPORT_N_SSD10")
		)
	)
	(footprint ""
		(layer "F.Cu")
		(at 337.051396 -99.177602 -90)
		(property "Reference" "PD96"
			(at 3.876802 -2.751074 90)
			(unlocked yes)
			(layer "F.SilkS")
			(effects
				(font
					(size 0.7874 0.5842)
					(thickness 0.1524)
				)
				(justify left)
			)
		)
		(property "Value" ""
			(at 0 0 270)
			(layer "F.Fab")
			(effects
				(font
					(size 1.27 1.27)
				)
			)
		)
		(duplicate_pad_numbers_are_jumpers no)
		(fp_line
			(start -3.656584 1.970024)
			(end 4.240784 1.970024)
			(stroke
				(width 0.1524)
				(type default)
			)
			(layer "F.SilkS")
		)
		(fp_line
			(start 4.240784 1.970024)
			(end 4.240784 -1.970024)
			(stroke
				(width 0.1524)
				(type default)
			)
			(layer "F.SilkS")
		)
		(fp_line
			(start -3.656584 -1.970024)
			(end -3.656584 1.970024)
			(stroke
				(width 0.1524)
				(type default)
			)
			(layer "F.SilkS")
		)
		(fp_line
			(start 4.240784 -1.970024)
			(end -3.656584 -1.970024)
			(stroke
				(width 0.1524)
				(type default)
			)
			(layer "F.SilkS")
		)
		(fp_rect
			(start 4.240784 1.970024)
			(end 3.580384 -1.970024)
			(stroke
				(width 0)
				(type default)
			)
			(fill yes)
			(layer "F.SilkS")
		)
		(fp_line
			(start -2.3749 1.970024)
			(end 2.3749 1.970024)
			(stroke
				(width 0.1)
				(type default)
			)
			(layer "F.Fab")
		)
		(fp_line
			(start 2.3749 1.970024)
			(end 2.3749 -1.970024)
			(stroke
				(width 0.1)
				(type default)
			)
			(layer "F.Fab")
		)
		(fp_line
			(start -2.3749 -1.970024)
			(end -2.3749 1.970024)
			(stroke
				(width 0.1)
				(type default)
			)
			(layer "F.Fab")
		)
		(fp_line
			(start 2.3749 -1.970024)
			(end -2.3749 -1.970024)
			(stroke
				(width 0.1)
				(type default)
			)
			(layer "F.Fab")
		)
		(fp_text user "+"
			(at -4.9784 -0.23495 270)
			(unlocked yes)
			(layer "F.Fab")
			(effects
				(font
					(size 1.905 1.4224)
					(thickness 0.1524)
				)
				(justify left)
			)
		)
		(fp_text user "-"
			(at 4.1656 -0.23495 270)
			(unlocked yes)
			(layer "F.Fab")
			(effects
				(font
					(size 1.905 1.4224)
					(thickness 0.1524)
				)
				(justify left)
			)
		)
		(pad "A" smd rect
			(at -2.450084 0 270)
			(size 2.159 2.2606)
			(layers "F.Cu" "F.Mask" "F.Paste")
			(net "GND")
		)
		(pad "C" smd rect
			(at 2.450084 0 270)
			(size 2.159 2.2606)
			(layers "F.Cu" "F.Mask" "F.Paste")
			(net "P12V_AUX")
		)
	)
)
